#ISCELL
  pure_quanta quanta_title_block_c *
  *
#ISCELL
  pure_quanta_power cad_note *
  *
#CELL
  pure_quanta genoa_sp5 *
  page42_i159
#ISCELL
  mstr_standard tap *
  page42_i160
#ISCELL
  mstr_standard offpage *
  page42_i161
#ISCELL
  mstr_standard offpage *
  page42_i162
#ISCELL
  mstr_standard tap *
  page42_i163
#ISCELL
  mstr_standard tap *
  page42_i164
#ISCELL
  mstr_standard tap *
  page42_i165
#ISCELL
  mstr_standard tap *
  page42_i166
#ISCELL
  mstr_standard tap *
  page42_i167
#ISCELL
  mstr_standard tap *
  page42_i168
#ISCELL
  mstr_standard tap *
  page42_i169
#ISCELL
  mstr_standard tap *
  page42_i170
#ISCELL
  mstr_standard tap *
  page42_i171
#ISCELL
  mstr_standard tap *
  page42_i172
#ISCELL
  mstr_standard tap *
  page42_i173
#ISCELL
  mstr_standard tap *
  page42_i174
#ISCELL
  mstr_standard tap *
  page42_i175
#ISCELL
  mstr_standard tap *
  page42_i176
#ISCELL
  mstr_standard tap *
  page42_i177
#ISCELL
  mstr_standard tap *
  page42_i178
#ISCELL
  mstr_standard tap *
  page42_i179
#ISCELL
  mstr_standard tap *
  page42_i180
#ISCELL
  mstr_standard tap *
  page42_i181
#ISCELL
  mstr_standard tap *
  page42_i182
#ISCELL
  mstr_standard tap *
  page42_i183
#ISCELL
  mstr_standard tap *
  page42_i184
#ISCELL
  mstr_standard tap *
  page42_i185
#ISCELL
  mstr_standard tap *
  page42_i186
#ISCELL
  mstr_standard tap *
  page42_i187
#ISCELL
  mstr_standard tap *
  page42_i188
#ISCELL
  mstr_standard tap *
  page42_i189
#ISCELL
  mstr_standard tap *
  page42_i190
#ISCELL
  mstr_standard tap *
  page42_i191
#ISCELL
  mstr_standard tap *
  page42_i192
#ISCELL
  mstr_standard tap *
  page42_i193
#ISCELL
  mstr_standard tap *
  page42_i194
#ISCELL
  mstr_standard tap *
  page42_i195
#ISCELL
  mstr_standard tap *
  page42_i196
#ISCELL
  mstr_standard tap *
  page42_i197
#ISCELL
  mstr_standard tap *
  page42_i198
#ISCELL
  mstr_standard tap *
  page42_i199
#ISCELL
  mstr_standard offpage *
  page42_i200
#ISCELL
  mstr_standard offpage *
  page42_i201
#ISCELL
  mstr_standard tap *
  page42_i202
#ISCELL
  mstr_standard tap *
  page42_i203
#ISCELL
  mstr_standard tap *
  page42_i204
#ISCELL
  mstr_standard tap *
  page42_i205
#ISCELL
  mstr_standard tap *
  page42_i206
#ISCELL
  mstr_standard tap *
  page42_i207
#ISCELL
  mstr_standard tap *
  page42_i208
#ISCELL
  mstr_standard tap *
  page42_i209
#ISCELL
  mstr_standard tap *
  page42_i210
#ISCELL
  mstr_standard tap *
  page42_i211
#ISCELL
  mstr_standard tap *
  page42_i212
#ISCELL
  mstr_standard tap *
  page42_i213
#ISCELL
  mstr_standard tap *
  page42_i214
#ISCELL
  mstr_standard tap *
  page42_i215
#ISCELL
  mstr_standard tap *
  page42_i216
#ISCELL
  mstr_standard tap *
  page42_i217
#ISCELL
  mstr_standard tap *
  page42_i218
#ISCELL
  mstr_standard tap *
  page42_i219
#ISCELL
  mstr_standard tap *
  page42_i220
#ISCELL
  mstr_standard tap *
  page42_i221
#ISCELL
  mstr_standard tap *
  page42_i222
#ISCELL
  mstr_standard tap *
  page42_i223
#ISCELL
  mstr_standard tap *
  page42_i224
#ISCELL
  mstr_standard tap *
  page42_i225
#ISCELL
  mstr_standard tap *
  page42_i226
#ISCELL
  mstr_standard tap *
  page42_i227
#ISCELL
  mstr_standard tap *
  page42_i228
#ISCELL
  mstr_standard tap *
  page42_i229
#ISCELL
  mstr_standard tap *
  page42_i230
#ISCELL
  mstr_standard tap *
  page42_i231
#ISCELL
  mstr_standard tap *
  page42_i232
#ISCELL
  mstr_standard tap *
  page42_i233
#ISCELL
  mstr_standard tap *
  page42_i234
#ISCELL
  mstr_standard tap *
  page42_i235
#ISCELL
  mstr_standard tap *
  page42_i236
#ISCELL
  mstr_standard tap *
  page42_i237
#ISCELL
  mstr_standard tap *
  page42_i238
#ISCELL
  mstr_standard tap *
  page42_i239
#ISCELL
  mstr_standard tap *
  page42_i240
#ISCELL
  mstr_standard tap *
  page42_i241
#ISCELL
  mstr_standard tap *
  page42_i242
#ISCELL
  mstr_standard tap *
  page42_i243
#ISCELL
  mstr_standard tap *
  page42_i244
#ISCELL
  mstr_standard tap *
  page42_i245
#ISCELL
  mstr_standard tap *
  page42_i246
#ISCELL
  mstr_standard tap *
  page42_i247
#ISCELL
  mstr_standard tap *
  page42_i248
#ISCELL
  mstr_standard tap *
  page42_i249
#ISCELL
  mstr_standard tap *
  page42_i250
#ISCELL
  mstr_standard tap *
  page42_i251
#ISCELL
  mstr_standard tap *
  page42_i252
#ISCELL
  mstr_standard tap *
  page42_i253
#ISCELL
  mstr_standard tap *
  page42_i254
#ISCELL
  mstr_standard tap *
  page42_i255
#ISCELL
  mstr_standard tap *
  page42_i256
#ISCELL
  mstr_standard tap *
  page42_i257
#ISCELL
  mstr_standard tap *
  page42_i258
#ISCELL
  mstr_standard tap *
  page42_i259
#ISCELL
  mstr_standard tap *
  page42_i260
#ISCELL
  mstr_standard tap *
  page42_i261
#ISCELL
  mstr_standard tap *
  page42_i262
#ISCELL
  mstr_standard tap *
  page42_i263
#ISCELL
  mstr_standard tap *
  page42_i264
#ISCELL
  mstr_standard tap *
  page42_i265
#ISCELL
  mstr_standard tap *
  page42_i266
#ISCELL
  mstr_standard tap *
  page42_i267
#ISCELL
  mstr_standard tap *
  page42_i268
#ISCELL
  mstr_standard tap *
  page42_i269
#ISCELL
  mstr_standard tap *
  page42_i270
#ISCELL
  mstr_standard tap *
  page42_i271
#ISCELL
  mstr_standard tap *
  page42_i272
#ISCELL
  mstr_standard tap *
  page42_i273
#ISCELL
  mstr_standard tap *
  page42_i274
#ISCELL
  mstr_standard tap *
  page42_i275
#ISCELL
  mstr_standard tap *
  page42_i276
#ISCELL
  mstr_standard tap *
  page42_i277
#ISCELL
  mstr_standard tap *
  page42_i278
#ISCELL
  mstr_standard tap *
  page42_i279
#ISCELL
  mstr_standard tap *
  page42_i280
#ISCELL
  mstr_standard tap *
  page42_i281
#ISCELL
  mstr_standard tap *
  page42_i282
#ISCELL
  mstr_standard tap *
  page42_i283
#ISCELL
  standard offpage *
  page42_i284
#ISCELL
  standard offpage *
  page42_i285
#ISCELL
  standard offpage *
  page42_i286
#ISCELL
  standard offpage *
  page42_i287
#ISCELL
  mstr_standard tap *
  page42_i288
#ISCELL
  mstr_standard tap *
  page42_i289
#ISCELL
  mstr_standard tap *
  page42_i290
#ISCELL
  mstr_standard tap *
  page42_i291
#ISCELL
  mstr_standard tap *
  page42_i292
#ISCELL
  mstr_standard tap *
  page42_i293
#ISCELL
  mstr_standard tap *
  page42_i294
#ISCELL
  mstr_standard tap *
  page42_i295
#ISCELL
  mstr_standard tap *
  page42_i296
#ISCELL
  mstr_standard tap *
  page42_i297
#ISCELL
  mstr_standard tap *
  page42_i298
#ISCELL
  mstr_standard tap *
  page42_i299
#ISCELL
  mstr_standard tap *
  page42_i300
#ISCELL
  mstr_standard tap *
  page42_i301
#ISCELL
  standard offpage *
  page42_i302
#ISCELL
  standard offpage *
  page42_i303
#ISCELL
  standard offpage *
  page42_i304
#ISCELL
  standard offpage *
  page42_i305
#ISCELL
  standard offpage *
  page42_i306
#ISCELL
  standard offpage *
  page42_i307
#ISCELL
  standard offpage *
  page42_i308
#ISCELL
  mstr_standard offpage *
  page42_i309
#ISCELL
  standard offpage *
  page42_i310
#ISCELL
  standard offpage *
  page42_i311
#ISCELL
  standard offpage *
  page42_i312
#ISCELL
  standard offpage *
  page42_i313
#CELL
  pure_quanta q_res *
  page42_i314
#ISCELL
  standard offpage *
  page42_i315
#ISCELL
  mstr_standard offpage *
  page42_i316
